# S9S_MB_2U (Grand Teton) — schematic netlist excerpt (pin names and nets, part order shuffled) for the footprints in the layout excerpt that follows; sources: Cadence DE-HDL packaged netlist, KiCad conversion of 03242023_DA0F0TMBIJ0_F0T_Motherboard_J_brd_V01_OCP.brd

R78  Q_RES  15.4K 1% CHIP  pkg 0402LF  page 107 : A = PD_CHE_CPU1_DIMM2_SAA ; B = GND
R4104  Q_RES  10K 1% CHIP  pkg 0402LF  page 184 : A = PD_GPP_M_16 ; B = GND

(kicad_pcb
	(version 20260206)
	(generator "pcbnew")
	(generator_version "10.0")
	(general
		(thickness 1.6)
		(legacy_teardrops no)
	)
	(paper "A4")
	(title_block
		(title "03242023_DA0F0TMBIJ0_F0T_Motherboard_J_brd_V01_OCP.brd")
		(comment 1 "Grand Teton / footprints 5188-5189 of 6105")
	)
	(layers
		(0 "F.Cu" signal "TOP")
		(4 "In1.Cu" signal "GND")
		(6 "In2.Cu" signal "IN1")
		(8 "In3.Cu" signal "GND1")
		(10 "In4.Cu" signal "IN2")
		(12 "In5.Cu" signal "GND2")
		(14 "In6.Cu" signal "IN3")
		(16 "In7.Cu" signal "GND3")
		(18 "In8.Cu" signal "VCC")
		(20 "In9.Cu" signal "VCC1")
		(22 "In10.Cu" signal "GND4")
		(24 "In11.Cu" signal "IN4")
		(26 "In12.Cu" signal "GND5")
		(28 "In13.Cu" signal "IN5")
		(30 "In14.Cu" signal "GND6")
		(32 "In15.Cu" signal "IN6")
		(34 "In16.Cu" signal "GND7")
		(2 "B.Cu" signal "BOTTOM")
		(9 "F.Adhes" user "F.Adhesive")
		(11 "B.Adhes" user "B.Adhesive")
		(13 "F.Paste" user "Package Geometry/Pastemask Top")
		(15 "B.Paste" user "Package Geometry/Pastemask Bottom")
		(5 "F.SilkS" user "Ref Des/Silkscreen Top")
		(7 "B.SilkS" user "Ref Des/Silkscreen Bottom")
		(1 "F.Mask" user "Board Geometry/Soldermask Top")
		(3 "B.Mask" user "Board Geometry/Soldermask Bottom")
		(17 "Dwgs.User" user "User.Drawings")
		(19 "Cmts.User" user "User.Comments")
		(21 "Eco1.User" user "User.Eco1")
		(23 "Eco2.User" user "User.Eco2")
		(25 "Edge.Cuts" user "Board Geometry/Outline")
		(27 "Margin" user)
		(31 "F.CrtYd" user "Package Geometry/Place Bound Top")
		(29 "B.CrtYd" user "Package Geometry/Place Bound Bottom")
		(35 "F.Fab" user "Ref Des/Assembly Top")
		(33 "B.Fab" user "Ref Des/Assembly Bottom")
	)
	(footprint ""
		(layer "B.Cu")
		(at 311.84088 -55.336948)
		(property "Reference" "R4104"
			(at 0 0 0)
			(layer "B.SilkS")
			(hide yes)
			(effects
				(font
					(size 1.27 1.27)
				)
				(justify mirror)
			)
		)
		(property "Value" ""
			(at 0 0 0)
			(layer "B.Fab")
			(effects
				(font
					(size 1.27 1.27)
				)
				(justify mirror)
			)
		)
		(duplicate_pad_numbers_are_jumpers no)
		(fp_line
			(start -0.7874 -0.4064)
			(end -0.7874 0.4064)
			(stroke
				(width 0.1524)
				(type default)
			)
			(layer "B.SilkS")
		)
		(fp_line
			(start -0.7874 0.4064)
			(end 0.7874 0.4064)
			(stroke
				(width 0.1524)
				(type default)
			)
			(layer "B.SilkS")
		)
		(fp_line
			(start 0.7874 -0.4064)
			(end -0.7874 -0.4064)
			(stroke
				(width 0.1524)
				(type default)
			)
			(layer "B.SilkS")
		)
		(fp_line
			(start 0.7874 0.4064)
			(end 0.7874 -0.4064)
			(stroke
				(width 0.1524)
				(type default)
			)
			(layer "B.SilkS")
		)
		(fp_line
			(start -0.67945 -0.3048)
			(end -0.67945 0.3048)
			(stroke
				(width 0.1)
				(type default)
			)
			(layer "B.Fab")
		)
		(fp_line
			(start -0.67945 0.3048)
			(end -0.120396 0.3048)
			(stroke
				(width 0.1)
				(type default)
			)
			(layer "B.Fab")
		)
		(fp_line
			(start -0.12065 -0.3048)
			(end -0.67945 -0.3048)
			(stroke
				(width 0.1)
				(type default)
			)
			(layer "B.Fab")
		)
		(fp_line
			(start -0.12065 -0.2794)
			(end -0.12065 -0.3048)
			(stroke
				(width 0.1)
				(type default)
			)
			(layer "B.Fab")
		)
		(fp_line
			(start -0.120396 0.2794)
			(end 0.12065 0.2794)
			(stroke
				(width 0.1)
				(type default)
			)
			(layer "B.Fab")
		)
		(fp_line
			(start -0.120396 0.3048)
			(end -0.120396 0.2794)
			(stroke
				(width 0.1)
				(type default)
			)
			(layer "B.Fab")
		)
		(fp_line
			(start 0.12065 -0.305054)
			(end 0.12065 -0.2794)
			(stroke
				(width 0.1)
				(type default)
			)
			(layer "B.Fab")
		)
		(fp_line
			(start 0.12065 -0.2794)
			(end -0.12065 -0.2794)
			(stroke
				(width 0.1)
				(type default)
			)
			(layer "B.Fab")
		)
		(fp_line
			(start 0.12065 0.2794)
			(end 0.12065 0.3048)
			(stroke
				(width 0.1)
				(type default)
			)
			(layer "B.Fab")
		)
		(fp_line
			(start 0.12065 0.3048)
			(end 0.67945 0.3048)
			(stroke
				(width 0.1)
				(type default)
			)
			(layer "B.Fab")
		)
		(fp_line
			(start 0.67945 -0.305054)
			(end 0.12065 -0.305054)
			(stroke
				(width 0.1)
				(type default)
			)
			(layer "B.Fab")
		)
		(fp_line
			(start 0.67945 0.3048)
			(end 0.67945 -0.305054)
			(stroke
				(width 0.1)
				(type default)
			)
			(layer "B.Fab")
		)
		(pad "1" smd circle
			(at 0.40005 0 180)
			(size 0 0)
			(layers "B.Cu" "B.Mask" "B.Paste")
			(net "PD_GPP_M_16")
		)
		(pad "2" smd circle
			(at -0.40005 0 180)
			(size 0 0)
			(layers "B.Cu" "B.Mask" "B.Paste")
			(net "GND")
		)
	)
	(footprint ""
		(layer "B.Cu")
		(at 160.952942 -318.705992 -90)
		(property "Reference" "R78"
			(at 0 0 90)
			(layer "B.SilkS")
			(hide yes)
			(effects
				(font
					(size 1.27 1.27)
				)
				(justify mirror)
			)
		)
		(property "Value" ""
			(at 0 0 90)
			(layer "B.Fab")
			(effects
				(font
					(size 1.27 1.27)
				)
				(justify mirror)
			)
		)
		(duplicate_pad_numbers_are_jumpers no)
		(fp_line
			(start -0.7874 0.4064)
			(end 0.7874 0.4064)
			(stroke
				(width 0.1524)
				(type default)
			)
			(layer "B.SilkS")
		)
		(fp_line
			(start 0.7874 0.4064)
			(end 0.7874 -0.4064)
			(stroke
				(width 0.1524)
				(type default)
			)
			(layer "B.SilkS")
		)
		(fp_line
			(start -0.7874 -0.4064)
			(end -0.7874 0.4064)
			(stroke
				(width 0.1524)
				(type default)
			)
			(layer "B.SilkS")
		)
		(fp_line
			(start 0.7874 -0.4064)
			(end -0.7874 -0.4064)
			(stroke
				(width 0.1524)
				(type default)
			)
			(layer "B.SilkS")
		)
		(fp_line
			(start -0.67945 0.3048)
			(end -0.120396 0.3048)
			(stroke
				(width 0.1)
				(type default)
			)
			(layer "B.Fab")
		)
		(fp_line
			(start -0.120396 0.3048)
			(end -0.120396 0.2794)
			(stroke
				(width 0.1)
				(type default)
			)
			(layer "B.Fab")
		)
		(fp_line
			(start 0.12065 0.3048)
			(end 0.67945 0.3048)
			(stroke
				(width 0.1)
				(type default)
			)
			(layer "B.Fab")
		)
		(fp_line
			(start 0.67945 0.3048)
			(end 0.67945 -0.305054)
			(stroke
				(width 0.1)
				(type default)
			)
			(layer "B.Fab")
		)
		(fp_line
			(start -0.120396 0.2794)
			(end 0.12065 0.2794)
			(stroke
				(width 0.1)
				(type default)
			)
			(layer "B.Fab")
		)
		(fp_line
			(start 0.12065 0.2794)
			(end 0.12065 0.3048)
			(stroke
				(width 0.1)
				(type default)
			)
			(layer "B.Fab")
		)
		(fp_line
			(start -0.12065 -0.2794)
			(end -0.12065 -0.3048)
			(stroke
				(width 0.1)
				(type default)
			)
			(layer "B.Fab")
		)
		(fp_line
			(start 0.12065 -0.2794)
			(end -0.12065 -0.2794)
			(stroke
				(width 0.1)
				(type default)
			)
			(layer "B.Fab")
		)
		(fp_line
			(start -0.67945 -0.3048)
			(end -0.67945 0.3048)
			(stroke
				(width 0.1)
				(type default)
			)
			(layer "B.Fab")
		)
		(fp_line
			(start -0.12065 -0.3048)
			(end -0.67945 -0.3048)
			(stroke
				(width 0.1)
				(type default)
			)
			(layer "B.Fab")
		)
		(fp_line
			(start 0.12065 -0.305054)
			(end 0.12065 -0.2794)
			(stroke
				(width 0.1)
				(type default)
			)
			(layer "B.Fab")
		)
		(fp_line
			(start 0.67945 -0.305054)
			(end 0.12065 -0.305054)
			(stroke
				(width 0.1)
				(type default)
			)
			(layer "B.Fab")
		)
		(pad "1" smd circle
			(at 0.40005 0 90)
			(size 0 0)
			(layers "B.Cu" "B.Mask" "B.Paste")
			(net "PD_CHE_CPU1_DIMM2_SAA")
		)
		(pad "2" smd circle
			(at -0.40005 0 90)
			(size 0 0)
			(layers "B.Cu" "B.Mask" "B.Paste")
			(net "GND")
		)
	)
)
